# SCM (Grand Teton) — schematic netlist excerpt (pin names and nets, part order shuffled) for the footprints in the layout excerpt that follows; sources: Cadence DE-HDL packaged netlist, KiCad conversion of 12092022_DA0F0TMDCD0_F0T_Management_Board_D_brd_V3_OCP.brd

U25  LCMXO3LF2100C5BG256C  LCMXO3LF-2100C-5BG256C IC  pkg BGA256_0-8_14X14  page 34
  VCC_A1  = PVCCA_AUX_PLD
  NC1  = NC
  PT11C  = BSM_PRSNT_R1_N
  PT10A  = RST_PLTRST_R1_N
  PT11A  = RST_RSMRST_N
  \pt12d||tdi\  = JTAG_SCM_PLD_TDI
  \pt16c||tck\  = JTAG_SCM_PLD_TCK
  \pt17b||pclkc0_1\  = IRQ_BMC_PCH_NMI_R_N
  \pt18c||scl||pclkt0_0\  = SMB_BMC_MM16_R3_SCL
  PT19B  = NC
  PT21A  = RST_EXTRST_R_N
  PT22B  = FM_ADR_COMPLETE
  \pt24c||initn\  = PU_FPGA_NSTATUS
  PT22D  = SGPIO_CLK_PLD_0
  PT24B  = FM_THERMTRIP_DLY_LVC1_R_N
  VCC_A16  = PVCCA_AUX_PLD
  PL1C  = NC
  GND_B2  = GND
  PT9C  = IRQ_BMC_CPU_NMI_R
  PT11D  = RST_PCA9548_SENSOR_N
  PT9B  = FM_TPM_PRSNT_1_R_N
  PT11B  = FM_JTAG_BMC_MUX_SEL_R2
  PT13A  = IRQ_UV_DETECT_N
  \pt16d||tms\  = JTAG_SCM_PLD_TMS
  PT19A  = IRQ_PCH_SCI_WHEA_N
  \pt20d||programn\  = PU_PT20D
  PT22A  = IRQ_OC_DETECT_N
  PT23B  = SGPIO_PLD_LD_0
  PT22C  = IRQ_OC_DETECT_EN_N
  PT24A  = SGPIO_PLD_DI_0
  GND_B15  = GND
  PR1D  = FM_PECI_SEL_N
  PL2C  = NC
  PL1D  = NC
  GND_C3  = GND
  PT9A  = FM_TPM_PRSNT_0_R_N
  PT10B  = PWRGD_PSU_AC_PWROK_PLD
  \pt12c||tdo\  = JTAG_SCM_PLD_TDO
  PT13B  = RST_BMC_RSTBTN_OUT_N
  \pt17a||pclkt0_1\  = CLK_25M_OSC_FPGA
  \pt18d||sda||pclkc0_0\  = SMB_BMC_MM16_R3_SDA
  \pt20c||jtagenb\  = JTAG_SCM_PLD_R_JTAGEN
  PT21B  = PWRGD_CPUPWRGD_LVC1
  PT23A  = SGPIO_PLD_DO_0
  \pt24d||done\  = PU_FPGA_CONFIG_DONE
  GND_C14  = GND
  PR1C  = VOL_SEN_ALERT_R
  PR2C  = SMB_BMC_ALERT3_R1_N
  \pl1b||l_gpllc_fb\  = NC
  PL2D  = NC
  \pl1a||l_gpllt_fb\  = NC
  GND_D4  = GND
  VCCIO0_D5  = VCCIO0
  PT12A  = FM_BMC_DBP_PRESENT_N
  PT13D  = FM_ME_BT_DONE
  PT17C  = FM_PCH_BMC_THERMTRIP_N
  PT18B  = NC
  PT20A  = NC
  PT21D  = IRQ_CPU1_VRHOT_N
  VCCIO0_D12  = VCCIO0
  GND_D13  = GND
  PR1A  = H_CPU0_MEMTRIP_LVC1_N
  PR2D  = SMB_BMC_ALERT4_R1_N
  PR2A  = H_CPU1_MEMTRIP_LVC1_N
  \pl3a||pclkt5_0\  = NC
  \pl2a||l_gpllt_in\  = NC
  \pl2b||l_gpllc_in\  = NC
  VCCIO5  = VCCIO5
  GND_E5  = GND
  PT13C  = BMC_CPLD_GPIO_2_R2
  PT12B  = PWRGD_PCH_PWROK
  PT16B  = FM_BIOS_POST_CMPLT_BMC_N
  PT17D  = H_CPU1_PROCHOT_LVC1_R_N
  PT20B  = FM_CPU_MSMI_CATERR_LVT3_PLD_N
  PT19D  = TP_PLD_19D
  GND_E12  = GND
  VCCIO1_E13  = VCCIO1
  PR2B  = IRQ_SGPIO_R_N
  PR1B  = FM_SPD_REMOTE_EN_R
  PR3A  = RST_SGPIO_RESET_R_N
  PL4B  = NC
  \pl3b||pclkc5_0\  = NC
  PL4A  = NC
  PL3C  = NC
  PL5C  = NC
  GND_F6  = GND
  PT16A  = FM_PCIE_M2_SSD0_PRSNT_N
  PT18A  = RST_SRST_PLD_BMC_R2_N
  PT19C  = NC
  PT21C  = IRQ_CPU0_VRHOT_N
  GND_F11  = GND
  PR4C  = TP_PLD_L3
  PR3C  = SMB_BMC_ALERT9_R1_N
  PR4A  = BMC_CPLD_GPIO_8_R2
  PR3B  = BMC_CPLD_GPIO_7_R2
  PR4B  = NC
  PL6A  = NC
  PL5A  = NC
  PL5B  = NC
  PL4D  = NC
  PL4C  = NC
  PL3D  = NC
  VCC_G7  = PVCCA_AUX_PLD
  VCCIO0_G8  = VCCIO0
  VCCIO0_G9  = VCCIO0
  VCC_G10  = PVCCA_AUX_PLD
  PR5C  = FM_SLPS3_GF_R_N
  PR3D  = SMB_BMC_ALERT10_R1_N
  PR4D  = RST_BMC_SELF_HW_R2
  PR5B  = NC
  PR5A  = NC
  PR6A  = BMC_CPLD_GPIO_12_R2
  PL7B  = NC
  PL6B  = NC
  PL7A  = NC
  PL6C  = NC
  PL9C  = NC
  PL5D  = NC
  VCCIO4_H7  = VCCIO4
  GND_H8  = GND
  GND_H9  = GND
  VCCIO1_H10  = VCCIO1
  PR9C  = RST_MB_STBY_R_N
  PR5D  = RST_ROT_CPU_R_N
  PR6C  = FM_ESPI_PLD_R_EN
  \pr7a||pclkt1_0\  = NC
  PR6B  = BMC_CPLD_GPIO_13_R2
  \pr7b||pclkc1_0\  = NC
  \pl7c||pclkt4_0\  = NC
  PL9A  = NC
  \pl7d||pclkc4_0\  = NC
  PL9D  = NC
  PL10C  = NC
  PL6D  = NC
  VCCIO4_J7  = VCCIO4
  GND_J8  = GND
  GND_J9  = GND
  VCCIO1_J10  = VCCIO1
  PR10C  = NC
  PR6D  = FM_THROTTLE_R_N
  PR9D  = FM_ADR_TRIGGER_N
  PR7D  = H_CPU0_PROCHOT_LVC1_R_N
  PR9A  = RST_BMC_HW_R
  PR7C  = FM_PMBUS_ALERT_EN
  PL9B  = NC
  PL10B  = NC
  PL10A  = NC
  PL11C  = NC
  PL12C  = NC
  PL10D  = NC
  VCC_K7  = PVCCA_AUX_PLD
  VCCIO2_K8  = VCCIO2
  VCCIO2_K9  = VCCIO2
  VCC_K10  = PVCCA_AUX_PLD
  PR12C  = FM_PCHHOT_R_N
  PR11D  = FM_BIOS_DEBUG_EN_N
  PR11C  = FM_BMC_READY_PLD_N
  PR10A  = FM_PWR_R_BTN
  PR10B  = PWRGD_SYS_PWROK_PLD
  PR9B  = NC
  PL11A  = NC
  \pl12a||pclkt3_0\  = NC
  PL11B  = NC
  PL12D  = NC
  PL11D  = NC
  GND_L6  = GND
  PB8D  = NC_FM_PFR_NO_SERVICE_ACT_N
  PB11D  = FM_PFR_DSW_PWROK_N
  PB12D  = FM_BMC_CPU_FBRK_OUT_R_N
  PB18D  = FM_UARTSW_MSB_R_N
  GND_L11  = GND
  PR10D  = FM_BMC_EN_DET_R
  PR12D  = FM_BMC_ONCTL_R_N
  PR11B  = SMB_BMC_ALERT12_N
  PR12A  = NC
  PR11A  = USB_OC0_REAR_R_N
  \pl12b||pclkc3_0\  = NC
  PL14A  = NC
  PL13A  = NC
  VCCIO3  = VCCIO3
  GND_M5  = GND
  PB11C  = BMC_MONITER
  PB9C  = CLK_GEN2_BMC_RC_OE_N
  PB16C  = PWRGD_P1V8_AUX_R1
  PB18C  = FM_UARTSW_LSB_R_N
  PB21C  = PU_FPGA_NCONFIG
  PB19D  = NC
  GND_M12  = GND
  VCCIO1_M13  = VCCIO1
  PR13A  = PWR_LED_CPLD
  PR13B  = PWRGD_P5V_AUX_R1
  PR12B  = NC
  PL13B  = NC
  PL13C  = NC
  PL14B  = NC
  GND_N4  = GND
  VCCIO2_N5  = VCCIO2
  PB8C  = FM_BMC_DEBUG_SW_R2_N
  PB9D  = IRQ_SML0_ALERT_R_N
  PB12C  = CLK_BUF1_GPU_FPGA_OE_R_N
  PB16D  = PWRGD_P3V3_RGM_R1
  PB19C  = NC
  PB21D  = NC
  VCCIO2_N12  = VCCIO2
  GND_N13  = GND
  PR14B  = PWRGD_P2V5_AUX_R1
  PR13C  = AC_PWR_BTN_R2_N
  PR14A  = PWRGD_P3V3_AUX_R1
  PL13D  = NC
  PL14D  = NC
  GND_P3  = GND
  PB3A  = FM_P12V_HSC_ENABLE_R2
  PB5B  = TP_PLD_C13
  \pb8a||mclk||cclk\  = FM_HDD_LED_N
  PB9B  = GPU_WP_HW_CTRL_R_N
  PB12A  = GPU_FPGA_RST_N
  \pb16b||pclkc2_1\  = PWRGD_P1V0_AUX_R1
  PB19A  = NC
  PB21B  = NC
  PB24A  = NC
  \pb25b||si||sispi\  = NC
  GND_P14  = GND
  PR14C  = NC
  PR13D  = NC
  PL14C  = NC
  GND_R2  = GND
  PB3D  = PWRGD_DSW_PWROK_R2
  PB6D  = FM_BMC_SUSACK_R2_N
  \pb5a||csspin\  = FM_DEBUG_PORT_R2_PRSNT_N
  PB6B  = FM_BMC_CRASHLOG_TRIG_R2_N
  PB9A  = GPU_NVS_PWR_BRAKE_R_N
  \pb11b||pclkc2_0\  = NC_FM_PFR_UPDATE_N
  PB18A  = NC
  PB19B  = NC
  PB22A  = NC
  \pb25a||sn\  = PU_PB25A
  PB22C  = NC
  PB25D  = SMB_BMC_MM16_R4_SDA
  GND_R15  = GND
  PR14D  = SMB_BMC_ALERT16_R2_N
  VCC_T1  = PVCCA_AUX_PLD
  PB3C  = FM_SOL_UART_CH_SEL_R2
  PB6C  = RST_WDTRST_PLD_R2_N
  PB3B  = NC
  PB6A  = IRQ_PCH_TPM_SPI_R2_N
  \pb8b||so||spiso\  = FM_PCH_BEEP_LED
  \pb11a||pclkt2_0\  = RST_PFR_OVR_RTC_R
  PB12B  = FM_JTAG_TCK_MUX_BMC_SEL
  \pb16a||pclkt2_1\  = PWRGD_P1V2_AUX_R1
  PB18B  = NC
  PB21A  = NC
  PB22B  = NC
  PB24B  = NC
  PB22D  = NC
  PB25C  = SMB_BMC_MM16_R4_SCL
  VCC_T16  = PVCCA_AUX_PLD

(kicad_pcb
	(version 20260206)
	(generator "pcbnew")
	(generator_version "10.0")
	(general
		(thickness 1.6)
		(legacy_teardrops no)
	)
	(paper "A4")
	(title_block
		(title "12092022_DA0F0TMDCD0_F0T_Management_Board_D_brd_V3_OCP.brd")
		(comment 1 "Grand Teton / footprint 162 of 1440 (U25), pads 237-256 of 256")
	)
	(layers
		(0 "F.Cu" signal "TOP")
		(4 "In1.Cu" signal "GND")
		(6 "In2.Cu" signal "IN1")
		(8 "In3.Cu" signal "GND1")
		(10 "In4.Cu" signal "IN2")
		(12 "In5.Cu" signal "VCC")
		(14 "In6.Cu" signal "VCC1")
		(16 "In7.Cu" signal "IN3")
		(18 "In8.Cu" signal "GND2")
		(20 "In9.Cu" signal "IN4")
		(22 "In10.Cu" signal "GND3")
		(2 "B.Cu" signal "BOTTOM")
		(9 "F.Adhes" user "F.Adhesive")
		(11 "B.Adhes" user "B.Adhesive")
		(13 "F.Paste" user "Package Geometry/Pastemask Top")
		(15 "B.Paste" user "Package Geometry/Pastemask Bottom")
		(5 "F.SilkS" user "Ref Des/Silkscreen Top")
		(7 "B.SilkS" user "Ref Des/Silkscreen Bottom")
		(1 "F.Mask" user "Board Geometry/Soldermask Top")
		(3 "B.Mask" user "Board Geometry/Soldermask Bottom")
		(17 "Dwgs.User" user "User.Drawings")
		(19 "Cmts.User" user "User.Comments")
		(21 "Eco1.User" user "User.Eco1")
		(23 "Eco2.User" user "User.Eco2")
		(25 "Edge.Cuts" user "Board Geometry/Outline")
		(27 "Margin" user)
		(31 "F.CrtYd" user "Package Geometry/Place Bound Top")
		(29 "B.CrtYd" user "Package Geometry/Place Bound Bottom")
		(35 "F.Fab" user "Ref Des/Assembly Top")
		(33 "B.Fab" user "Ref Des/Assembly Bottom")
	)
	(footprint ""
		(layer "F.Cu")
		(at 21.459444 -93.587062 180)
		(property "Reference" "U25"
			(at -10.595356 -8.218932 0)
			(unlocked yes)
			(layer "F.SilkS")
			(effects
				(font
					(size 0.7874 0.5842)
					(thickness 0.1524)
				)
				(justify left)
			)
		)
		(property "Value" ""
			(at 0 0 180)
			(layer "F.Fab")
			(effects
				(font
					(size 1.27 1.27)
				)
			)
		)
		(duplicate_pad_numbers_are_jumpers no)
		(pad "R13" smd circle
			(at 3.599942 5.199888 180)
			(size 0.4064 0.4064)
			(layers "F.Cu" "F.Mask" "F.Paste")
			(net "Net_259")
		)
		(pad "R14" smd circle
			(at 4.400042 5.199888 180)
			(size 0.4064 0.4064)
			(layers "F.Cu" "F.Mask" "F.Paste")
			(net "SMB_BMC_MM16_R4_SDA")
		)
		(pad "R15" smd circle
			(at 5.199888 5.199888 180)
			(size 0.4064 0.4064)
			(layers "F.Cu" "F.Mask" "F.Paste")
			(net "GND")
		)
		(pad "R16" smd circle
			(at 5.999988 5.199888 180)
			(size 0.4064 0.4064)
			(layers "F.Cu" "F.Mask" "F.Paste")
			(net "SMB_BMC_ALERT16_R2_N")
		)
		(pad "T1" smd circle
			(at -5.999988 5.999988 180)
			(size 0.4064 0.4064)
			(layers "F.Cu" "F.Mask" "F.Paste")
			(net "PVCCA_AUX_PLD")
		)
		(pad "T2" smd circle
			(at -5.199888 5.999988 180)
			(size 0.4064 0.4064)
			(layers "F.Cu" "F.Mask" "F.Paste")
			(net "FM_SOL_UART_CH_SEL_R2")
		)
		(pad "T3" smd circle
			(at -4.400042 5.999988 180)
			(size 0.4064 0.4064)
			(layers "F.Cu" "F.Mask" "F.Paste")
			(net "RST_WDTRST_PLD_R2_N")
		)
		(pad "T4" smd circle
			(at -3.599942 5.999988 180)
			(size 0.4064 0.4064)
			(layers "F.Cu" "F.Mask" "F.Paste")
			(net "Net_45")
		)
		(pad "T5" smd circle
			(at -2.800096 5.999988 180)
			(size 0.4064 0.4064)
			(layers "F.Cu" "F.Mask" "F.Paste")
			(net "IRQ_PCH_TPM_SPI_R2_N")
		)
		(pad "T6" smd circle
			(at -1.999996 5.999988 180)
			(size 0.4064 0.4064)
			(layers "F.Cu" "F.Mask" "F.Paste")
			(net "FM_PCH_BEEP_LED")
		)
		(pad "T7" smd circle
			(at -1.199896 5.999988 180)
			(size 0.4064 0.4064)
			(layers "F.Cu" "F.Mask" "F.Paste")
			(net "RST_PFR_OVR_RTC_R")
		)
		(pad "T8" smd circle
			(at -0.40005 5.999988 180)
			(size 0.4064 0.4064)
			(layers "F.Cu" "F.Mask" "F.Paste")
			(net "FM_JTAG_TCK_MUX_BMC_SEL")
		)
		(pad "T9" smd circle
			(at 0.40005 5.999988 180)
			(size 0.4064 0.4064)
			(layers "F.Cu" "F.Mask" "F.Paste")
			(net "PWRGD_P1V2_AUX_R1")
		)
		(pad "T10" smd circle
			(at 1.199896 5.999988 180)
			(size 0.4064 0.4064)
			(layers "F.Cu" "F.Mask" "F.Paste")
			(net "Net_249")
		)
		(pad "T11" smd circle
			(at 1.999996 5.999988 180)
			(size 0.4064 0.4064)
			(layers "F.Cu" "F.Mask" "F.Paste")
			(net "Net_254")
		)
		(pad "T12" smd circle
			(at 2.800096 5.999988 180)
			(size 0.4064 0.4064)
			(layers "F.Cu" "F.Mask" "F.Paste")
			(net "Net_258")
		)
		(pad "T13" smd circle
			(at 3.599942 5.999988 180)
			(size 0.4064 0.4064)
			(layers "F.Cu" "F.Mask" "F.Paste")
			(net "Net_262")
		)
		(pad "T14" smd circle
			(at 4.400042 5.999988 180)
			(size 0.4064 0.4064)
			(layers "F.Cu" "F.Mask" "F.Paste")
			(net "Net_260")
		)
		(pad "T15" smd circle
			(at 5.199888 5.999988 180)
			(size 0.4064 0.4064)
			(layers "F.Cu" "F.Mask" "F.Paste")
			(net "SMB_BMC_MM16_R4_SCL")
		)
		(pad "T16" smd circle
			(at 5.999988 5.999988 180)
			(size 0.4064 0.4064)
			(layers "F.Cu" "F.Mask" "F.Paste")
			(net "PVCCA_AUX_PLD")
		)
	)
)
